(kicad_pcb
	(version 20260206)
	(generator "pcbnew")
	(generator_version "10.0")
	(general
		(thickness 1.6)
		(legacy_teardrops no)
	)
	(paper "A4")
	(title_block
		(title "Wiwynn_Tioga_Pass_MB.brd")
		(comment 1 "Tioga Pass / footprints 3379-3385 of 4770")
	)
	(layers
		(0 "F.Cu" signal "TOP")
		(4 "In1.Cu" signal "L2GND")
		(6 "In2.Cu" signal "L3")
		(8 "In3.Cu" signal "L4GND")
		(10 "In4.Cu" signal "L5")
		(12 "In5.Cu" signal "L6GND")
		(14 "In6.Cu" signal "L7VCC")
		(16 "In7.Cu" signal "L8VCC")
		(18 "In8.Cu" signal "L9GND")
		(20 "In9.Cu" signal "L10")
		(22 "In10.Cu" signal "L11GND")
		(24 "In11.Cu" signal "L12")
		(26 "In12.Cu" signal "L13GND")
		(2 "B.Cu" signal "BOTTOM")
		(9 "F.Adhes" user "F.Adhesive")
		(11 "B.Adhes" user "B.Adhesive")
		(13 "F.Paste" user "Package Geometry/Pastemask Top")
		(15 "B.Paste" user "Package Geometry/Pastemask Bottom")
		(5 "F.SilkS" user "Ref Des/Silkscreen Top")
		(7 "B.SilkS" user "Ref Des/Silkscreen Bottom")
		(1 "F.Mask" user "Board Geometry/Soldermask Top")
		(3 "B.Mask" user "Board Geometry/Soldermask Bottom")
		(17 "Dwgs.User" user "User.Drawings")
		(19 "Cmts.User" user "User.Comments")
		(21 "Eco1.User" user "User.Eco1")
		(23 "Eco2.User" user "User.Eco2")
		(25 "Edge.Cuts" user "Board Geometry/Outline")
		(27 "Margin" user)
		(31 "F.CrtYd" user "Package Geometry/Place Bound Top")
		(29 "B.CrtYd" user "Package Geometry/Place Bound Bottom")
		(35 "F.Fab" user "Ref Des/Assembly Top")
		(33 "B.Fab" user "Ref Des/Assembly Bottom")
	)
	(footprint ""
		(layer "B.Cu")
		(at 104.5591 -135.4074 90)
		(property "Reference" "C8M1"
			(at -1.848866 0.752348 90)
			(unlocked yes)
			(layer "B.SilkS")
			(effects
				(font
					(size 1.27 0.9652)
					(thickness 0.1524)
				)
				(justify mirror)
			)
		)
		(property "Value" ""
			(at 0 0 90)
			(layer "B.Fab")
			(effects
				(font
					(size 1.27 1.27)
				)
				(justify mirror)
			)
		)
		(duplicate_pad_numbers_are_jumpers no)
		(fp_rect
			(start 0.500126 1.598422)
			(end -0.500126 -0.201422)
			(stroke
				(width 0)
				(type default)
			)
			(fill no)
			(layer "B.CrtYd")
		)
		(fp_line
			(start 0.500126 -0.201422)
			(end -0.500126 -0.201422)
			(stroke
				(width 0.1)
				(type default)
			)
			(layer "B.Fab")
		)
		(fp_line
			(start -0.500126 -0.201422)
			(end -0.500126 1.598422)
			(stroke
				(width 0.1)
				(type default)
			)
			(layer "B.Fab")
		)
		(fp_line
			(start 0.500126 1.598422)
			(end 0.500126 -0.201422)
			(stroke
				(width 0.1)
				(type default)
			)
			(layer "B.Fab")
		)
		(fp_line
			(start -0.500126 1.598422)
			(end 0.500126 1.598422)
			(stroke
				(width 0.1)
				(type default)
			)
			(layer "B.Fab")
		)
		(pad "1" smd rect
			(at 0 0)
			(size 0.889 0.9906)
			(layers "B.Cu" "B.Mask" "B.Paste")
			(net "PVDDQ_KLM")
		)
		(pad "2" smd rect
			(at 0 1.397)
			(size 0.889 0.9906)
			(layers "B.Cu" "B.Mask" "B.Paste")
			(net "GND")
		)
		(zone
			(layer "B.Cu")
			(hatch none 0.5)
			(connect_pads
				(clearance 0)
			)
			(min_thickness 0.25)
			(keepout
				(tracks not_allowed)
				(vias allowed)
				(pads allowed)
				(copperpour not_allowed)
				(footprints allowed)
			)
			(placement
				(enabled no)
				(sheetname "")
			)
			(fill
				(thermal_gap 0.5)
				(thermal_bridge_width 0.5)
				(island_removal_mode 0)
			)
			(polygon
				(pts
					(xy 105.5116 -135.9027) (xy 105.0036 -135.9027) (xy 105.0036 -134.9121) (xy 105.5116 -134.9121)
				)
			)
		)
		(zone
			(layer "B.Cu")
			(hatch none 0.5)
			(connect_pads
				(clearance 0)
			)
			(min_thickness 0.25)
			(keepout
				(tracks allowed)
				(vias not_allowed)
				(pads allowed)
				(copperpour not_allowed)
				(footprints allowed)
			)
			(placement
				(enabled no)
				(sheetname "")
			)
			(fill
				(thermal_gap 0.5)
				(thermal_bridge_width 0.5)
				(island_removal_mode 0)
			)
			(polygon
				(pts
					(xy 105.5116 -135.9027) (xy 105.0036 -135.9027) (xy 105.0036 -134.9121) (xy 105.5116 -134.9121)
				)
			)
		)
	)
	(footprint ""
		(layer "B.Cu")
		(at 32.258 -95.1484 90)
		(property "Reference" "R9N3"
			(at 0 0 90)
			(layer "B.SilkS")
			(hide yes)
			(effects
				(font
					(size 1.27 1.27)
				)
				(justify mirror)
			)
		)
		(property "Value" ""
			(at 0 0 90)
			(layer "B.Fab")
			(effects
				(font
					(size 1.27 1.27)
				)
				(justify mirror)
			)
		)
		(duplicate_pad_numbers_are_jumpers no)
		(fp_poly
			(pts
				(xy 0.2794 -0.1016) (xy -0.2794 -0.1016) (xy -0.2794 0.9906) (xy 0.2794 0.9906)
			)
			(stroke
				(width 0)
				(type default)
			)
			(fill no)
			(layer "B.CrtYd")
		)
		(fp_line
			(start 0.2794 -0.1016)
			(end 0.2794 0.9906)
			(stroke
				(width 0.1)
				(type default)
			)
			(layer "B.Fab")
		)
		(fp_line
			(start -0.2794 -0.1016)
			(end 0.2794 -0.1016)
			(stroke
				(width 0.1)
				(type default)
			)
			(layer "B.Fab")
		)
		(fp_line
			(start 0.2794 0.9906)
			(end -0.2794 0.9906)
			(stroke
				(width 0.1)
				(type default)
			)
			(layer "B.Fab")
		)
		(fp_line
			(start -0.2794 0.9906)
			(end -0.2794 -0.1016)
			(stroke
				(width 0.1)
				(type default)
			)
			(layer "B.Fab")
		)
		(pad "1" smd rect
			(at 0 0 270)
			(size 0.508 0.508)
			(layers "B.Cu" "B.Mask" "B.Paste")
			(net "VR_PVSA_CPU1_VCIN")
		)
		(pad "2" smd rect
			(at 0 0.889 270)
			(size 0.508 0.508)
			(layers "B.Cu" "B.Mask" "B.Paste")
			(net "P5V_STBY")
		)
		(zone
			(layer "B.Cu")
			(hatch none 0.5)
			(connect_pads
				(clearance 0)
			)
			(min_thickness 0.25)
			(keepout
				(tracks allowed)
				(vias not_allowed)
				(pads allowed)
				(copperpour not_allowed)
				(footprints allowed)
			)
			(placement
				(enabled no)
				(sheetname "")
			)
			(fill
				(thermal_gap 0.5)
				(thermal_bridge_width 0.5)
				(island_removal_mode 0)
			)
			(polygon
				(pts
					(xy 32.512 -95.4024) (xy 32.512 -94.8944) (xy 32.893 -94.8944) (xy 32.893 -95.4024)
				)
			)
		)
		(zone
			(layer "B.Cu")
			(hatch none 0.5)
			(connect_pads
				(clearance 0)
			)
			(min_thickness 0.25)
			(keepout
				(tracks not_allowed)
				(vias allowed)
				(pads allowed)
				(copperpour not_allowed)
				(footprints allowed)
			)
			(placement
				(enabled no)
				(sheetname "")
			)
			(fill
				(thermal_gap 0.5)
				(thermal_bridge_width 0.5)
				(island_removal_mode 0)
			)
			(polygon
				(pts
					(xy 32.893 -95.4024) (xy 32.893 -94.8944) (xy 32.512 -94.8944) (xy 32.512 -95.4024)
				)
			)
		)
	)
	(footprint ""
		(layer "B.Cu")
		(at 465.328 -116.49202)
		(property "Reference" "C1M7"
			(at 0 0 0)
			(layer "B.SilkS")
			(hide yes)
			(effects
				(font
					(size 1.27 1.27)
				)
				(justify mirror)
			)
		)
		(property "Value" ""
			(at 0 0 0)
			(layer "B.Fab")
			(effects
				(font
					(size 1.27 1.27)
				)
				(justify mirror)
			)
		)
		(duplicate_pad_numbers_are_jumpers no)
		(fp_rect
			(start -0.3048 0.9906)
			(end 0.3048 -0.1016)
			(stroke
				(width 0)
				(type default)
			)
			(fill no)
			(layer "B.CrtYd")
		)
		(fp_line
			(start -0.3048 -0.1016)
			(end 0.3048 -0.1016)
			(stroke
				(width 0.1)
				(type default)
			)
			(layer "B.Fab")
		)
		(fp_line
			(start -0.3048 0.9906)
			(end -0.3048 -0.1016)
			(stroke
				(width 0.1)
				(type default)
			)
			(layer "B.Fab")
		)
		(fp_line
			(start 0.3048 -0.1016)
			(end 0.3048 0.9906)
			(stroke
				(width 0.1)
				(type default)
			)
			(layer "B.Fab")
		)
		(fp_line
			(start 0.3048 0.9906)
			(end -0.3048 0.9906)
			(stroke
				(width 0.1)
				(type default)
			)
			(layer "B.Fab")
		)
		(pad "1" smd rect
			(at 0 0 180)
			(size 0.508 0.508)
			(layers "B.Cu" "B.Mask" "B.Paste")
			(net "P3E_CPU0_PE3_OCP_TXN<15>")
		)
		(pad "2" smd rect
			(at 0 0.889 180)
			(size 0.508 0.508)
			(layers "B.Cu" "B.Mask" "B.Paste")
			(net "P3E_OCP_CPU0_PE3_C_TXN<15>")
		)
		(zone
			(layer "B.Cu")
			(hatch none 0.5)
			(connect_pads
				(clearance 0)
			)
			(min_thickness 0.25)
			(keepout
				(tracks allowed)
				(vias not_allowed)
				(pads allowed)
				(copperpour not_allowed)
				(footprints allowed)
			)
			(placement
				(enabled no)
				(sheetname "")
			)
			(fill
				(thermal_gap 0.5)
				(thermal_bridge_width 0.5)
				(island_removal_mode 0)
			)
			(polygon
				(pts
					(xy 465.074 -115.85702) (xy 465.582 -115.85702) (xy 465.582 -116.23802) (xy 465.074 -116.23802)
				)
			)
		)
		(zone
			(layer "B.Cu")
			(hatch none 0.5)
			(connect_pads
				(clearance 0)
			)
			(min_thickness 0.25)
			(keepout
				(tracks not_allowed)
				(vias allowed)
				(pads allowed)
				(copperpour not_allowed)
				(footprints allowed)
			)
			(placement
				(enabled no)
				(sheetname "")
			)
			(fill
				(thermal_gap 0.5)
				(thermal_bridge_width 0.5)
				(island_removal_mode 0)
			)
			(polygon
				(pts
					(xy 465.074 -115.85702) (xy 465.582 -115.85702) (xy 465.582 -116.23802) (xy 465.074 -116.23802)
				)
			)
		)
	)
	(footprint ""
		(layer "B.Cu")
		(at 450.2277 -148.59 -90)
		(property "Reference" "C25W93"
			(at 0.8382 -0.67818 270)
			(unlocked yes)
			(layer "B.SilkS")
			(effects
				(font
					(size 0.4064 0.254)
					(thickness 0.1524)
				)
				(justify left mirror)
			)
		)
		(property "Value" ""
			(at 0 0 90)
			(layer "B.Fab")
			(effects
				(font
					(size 1.27 1.27)
				)
				(justify mirror)
			)
		)
		(duplicate_pad_numbers_are_jumpers no)
		(fp_poly
			(pts
				(xy -0.3048 -0.1016) (xy -0.3048 0.9906) (xy 0.3048 0.9906) (xy 0.3048 -0.1016)
			)
			(stroke
				(width 0)
				(type default)
			)
			(fill no)
			(layer "B.CrtYd")
		)
		(fp_line
			(start -0.3048 0.9906)
			(end -0.3048 -0.1016)
			(stroke
				(width 0.1)
				(type default)
			)
			(layer "B.Fab")
		)
		(fp_line
			(start 0.3048 0.9906)
			(end -0.3048 0.9906)
			(stroke
				(width 0.1)
				(type default)
			)
			(layer "B.Fab")
		)
		(fp_line
			(start -0.3048 -0.1016)
			(end 0.3048 -0.1016)
			(stroke
				(width 0.1)
				(type default)
			)
			(layer "B.Fab")
		)
		(fp_line
			(start 0.3048 -0.1016)
			(end 0.3048 0.9906)
			(stroke
				(width 0.1)
				(type default)
			)
			(layer "B.Fab")
		)
		(pad "1" smd rect
			(at 0 0 90)
			(size 0.508 0.508)
			(layers "B.Cu" "B.Mask" "B.Paste")
			(net "P0V7_GTL2014_VREF_6")
		)
		(pad "2" smd rect
			(at 0 0.889 90)
			(size 0.508 0.508)
			(layers "B.Cu" "B.Mask" "B.Paste")
			(net "GND")
		)
		(zone
			(layer "B.Cu")
			(hatch none 0.5)
			(connect_pads
				(clearance 0)
			)
			(min_thickness 0.25)
			(keepout
				(tracks not_allowed)
				(vias allowed)
				(pads allowed)
				(copperpour not_allowed)
				(footprints allowed)
			)
			(placement
				(enabled no)
				(sheetname "")
			)
			(fill
				(thermal_gap 0.5)
				(thermal_bridge_width 0.5)
				(island_removal_mode 0)
			)
			(polygon
				(pts
					(xy 449.5927 -148.336) (xy 449.5927 -148.844) (xy 449.9737 -148.844) (xy 449.9737 -148.336)
				)
			)
		)
		(zone
			(layer "B.Cu")
			(hatch none 0.5)
			(connect_pads
				(clearance 0)
			)
			(min_thickness 0.25)
			(keepout
				(tracks allowed)
				(vias not_allowed)
				(pads allowed)
				(copperpour not_allowed)
				(footprints allowed)
			)
			(placement
				(enabled no)
				(sheetname "")
			)
			(fill
				(thermal_gap 0.5)
				(thermal_bridge_width 0.5)
				(island_removal_mode 0)
			)
			(polygon
				(pts
					(xy 449.9737 -148.336) (xy 449.9737 -148.844) (xy 449.5927 -148.844) (xy 449.5927 -148.336)
				)
			)
		)
	)
	(footprint ""
		(layer "B.Cu")
		(at 330.08316 -67.26936 90)
		(property "Reference" "R4P15"
			(at 0 0 90)
			(layer "B.SilkS")
			(hide yes)
			(effects
				(font
					(size 1.27 1.27)
				)
				(justify mirror)
			)
		)
		(property "Value" ""
			(at 0 0 90)
			(layer "B.Fab")
			(effects
				(font
					(size 1.27 1.27)
				)
				(justify mirror)
			)
		)
		(duplicate_pad_numbers_are_jumpers no)
		(fp_poly
			(pts
				(xy 0.2794 -0.1016) (xy -0.2794 -0.1016) (xy -0.2794 0.9906) (xy 0.2794 0.9906)
			)
			(stroke
				(width 0)
				(type default)
			)
			(fill no)
			(layer "B.CrtYd")
		)
		(fp_line
			(start 0.2794 -0.1016)
			(end 0.2794 0.9906)
			(stroke
				(width 0.1)
				(type default)
			)
			(layer "B.Fab")
		)
		(fp_line
			(start -0.2794 -0.1016)
			(end 0.2794 -0.1016)
			(stroke
				(width 0.1)
				(type default)
			)
			(layer "B.Fab")
		)
		(fp_line
			(start 0.2794 0.9906)
			(end -0.2794 0.9906)
			(stroke
				(width 0.1)
				(type default)
			)
			(layer "B.Fab")
		)
		(fp_line
			(start -0.2794 0.9906)
			(end -0.2794 -0.1016)
			(stroke
				(width 0.1)
				(type default)
			)
			(layer "B.Fab")
		)
		(pad "1" smd rect
			(at 0 0 270)
			(size 0.508 0.508)
			(layers "B.Cu" "B.Mask" "B.Paste")
			(net "PVCCIO_CPU0")
		)
		(pad "2" smd rect
			(at 0 0.889 270)
			(size 0.508 0.508)
			(layers "B.Cu" "B.Mask" "B.Paste")
			(net "XDP_CPU_MBP1_N")
		)
		(zone
			(layer "B.Cu")
			(hatch none 0.5)
			(connect_pads
				(clearance 0)
			)
			(min_thickness 0.25)
			(keepout
				(tracks allowed)
				(vias not_allowed)
				(pads allowed)
				(copperpour not_allowed)
				(footprints allowed)
			)
			(placement
				(enabled no)
				(sheetname "")
			)
			(fill
				(thermal_gap 0.5)
				(thermal_bridge_width 0.5)
				(island_removal_mode 0)
			)
			(polygon
				(pts
					(xy 330.33716 -67.52336) (xy 330.33716 -67.01536) (xy 330.71816 -67.01536) (xy 330.71816 -67.52336)
				)
			)
		)
		(zone
			(layer "B.Cu")
			(hatch none 0.5)
			(connect_pads
				(clearance 0)
			)
			(min_thickness 0.25)
			(keepout
				(tracks not_allowed)
				(vias allowed)
				(pads allowed)
				(copperpour not_allowed)
				(footprints allowed)
			)
			(placement
				(enabled no)
				(sheetname "")
			)
			(fill
				(thermal_gap 0.5)
				(thermal_bridge_width 0.5)
				(island_removal_mode 0)
			)
			(polygon
				(pts
					(xy 330.71816 -67.52336) (xy 330.71816 -67.01536) (xy 330.33716 -67.01536) (xy 330.33716 -67.52336)
				)
			)
		)
	)
	(footprint ""
		(layer "B.Cu")
		(at 339.717126 -90.049604 90)
		(property "Reference" "R3N19"
			(at 0 0 90)
			(layer "B.SilkS")
			(hide yes)
			(effects
				(font
					(size 1.27 1.27)
				)
				(justify mirror)
			)
		)
		(property "Value" ""
			(at 0 0 90)
			(layer "B.Fab")
			(effects
				(font
					(size 1.27 1.27)
				)
				(justify mirror)
			)
		)
		(duplicate_pad_numbers_are_jumpers no)
		(fp_poly
			(pts
				(xy 0.2794 -0.1016) (xy -0.2794 -0.1016) (xy -0.2794 0.9906) (xy 0.2794 0.9906)
			)
			(stroke
				(width 0)
				(type default)
			)
			(fill no)
			(layer "B.CrtYd")
		)
		(fp_line
			(start 0.2794 -0.1016)
			(end 0.2794 0.9906)
			(stroke
				(width 0.1)
				(type default)
			)
			(layer "B.Fab")
		)
		(fp_line
			(start -0.2794 -0.1016)
			(end 0.2794 -0.1016)
			(stroke
				(width 0.1)
				(type default)
			)
			(layer "B.Fab")
		)
		(fp_line
			(start 0.2794 0.9906)
			(end -0.2794 0.9906)
			(stroke
				(width 0.1)
				(type default)
			)
			(layer "B.Fab")
		)
		(fp_line
			(start -0.2794 0.9906)
			(end -0.2794 -0.1016)
			(stroke
				(width 0.1)
				(type default)
			)
			(layer "B.Fab")
		)
		(pad "1" smd rect
			(at 0 0 270)
			(size 0.508 0.508)
			(layers "B.Cu" "B.Mask" "B.Paste")
			(net "VSENSE_PVCCIO_CPU0_AVSP")
		)
		(pad "2" smd rect
			(at 0 0.889 270)
			(size 0.508 0.508)
			(layers "B.Cu" "B.Mask" "B.Paste")
			(net "VR_PVCCIO_CPU0_AVSP")
		)
		(zone
			(layer "B.Cu")
			(hatch none 0.5)
			(connect_pads
				(clearance 0)
			)
			(min_thickness 0.25)
			(keepout
				(tracks allowed)
				(vias not_allowed)
				(pads allowed)
				(copperpour not_allowed)
				(footprints allowed)
			)
			(placement
				(enabled no)
				(sheetname "")
			)
			(fill
				(thermal_gap 0.5)
				(thermal_bridge_width 0.5)
				(island_removal_mode 0)
			)
			(polygon
				(pts
					(xy 339.971126 -90.303604) (xy 339.971126 -89.795604) (xy 340.352126 -89.795604) (xy 340.352126 -90.303604)
				)
			)
		)
		(zone
			(layer "B.Cu")
			(hatch none 0.5)
			(connect_pads
				(clearance 0)
			)
			(min_thickness 0.25)
			(keepout
				(tracks not_allowed)
				(vias allowed)
				(pads allowed)
				(copperpour not_allowed)
				(footprints allowed)
			)
			(placement
				(enabled no)
				(sheetname "")
			)
			(fill
				(thermal_gap 0.5)
				(thermal_bridge_width 0.5)
				(island_removal_mode 0)
			)
			(polygon
				(pts
					(xy 340.352126 -90.303604) (xy 340.352126 -89.795604) (xy 339.971126 -89.795604) (xy 339.971126 -90.303604)
				)
			)
		)
	)
	(footprint ""
		(layer "B.Cu")
		(at 13.11402 -100.46208 90)
		(property "Reference" "C9N14"
			(at 0 0 90)
			(layer "B.SilkS")
			(hide yes)
			(effects
				(font
					(size 1.27 1.27)
				)
				(justify mirror)
			)
		)
		(property "Value" ""
			(at 0 0 90)
			(layer "B.Fab")
			(effects
				(font
					(size 1.27 1.27)
				)
				(justify mirror)
			)
		)
		(duplicate_pad_numbers_are_jumpers no)
		(fp_poly
			(pts
				(xy -0.3048 -0.1016) (xy -0.3048 0.9906) (xy 0.3048 0.9906) (xy 0.3048 -0.1016)
			)
			(stroke
				(width 0)
				(type default)
			)
			(fill no)
			(layer "B.CrtYd")
		)
		(fp_line
			(start 0.3048 -0.1016)
			(end 0.3048 0.9906)
			(stroke
				(width 0.1)
				(type default)
			)
			(layer "B.Fab")
		)
		(fp_line
			(start -0.3048 -0.1016)
			(end 0.3048 -0.1016)
			(stroke
				(width 0.1)
				(type default)
			)
			(layer "B.Fab")
		)
		(fp_line
			(start 0.3048 0.9906)
			(end -0.3048 0.9906)
			(stroke
				(width 0.1)
				(type default)
			)
			(layer "B.Fab")
		)
		(fp_line
			(start -0.3048 0.9906)
			(end -0.3048 -0.1016)
			(stroke
				(width 0.1)
				(type default)
			)
			(layer "B.Fab")
		)
		(pad "1" smd rect
			(at 0 0 270)
			(size 0.508 0.508)
			(layers "B.Cu" "B.Mask" "B.Paste")
			(net "P3E_CPU1_PE3_MP_C_TXP<12>")
		)
		(pad "2" smd rect
			(at 0 0.889 270)
			(size 0.508 0.508)
			(layers "B.Cu" "B.Mask" "B.Paste")
			(net "P3E_CPU1_PE3_MP_TXP<12>")
		)
		(zone
			(layer "B.Cu")
			(hatch none 0.5)
			(connect_pads
				(clearance 0)
			)
			(min_thickness 0.25)
			(keepout
				(tracks allowed)
				(vias not_allowed)
				(pads allowed)
				(copperpour not_allowed)
				(footprints allowed)
			)
			(placement
				(enabled no)
				(sheetname "")
			)
			(fill
				(thermal_gap 0.5)
				(thermal_bridge_width 0.5)
				(island_removal_mode 0)
			)
			(polygon
				(pts
					(xy 13.36802 -100.71608) (xy 13.36802 -100.20808) (xy 13.74902 -100.20808) (xy 13.74902 -100.71608)
				)
			)
		)
		(zone
			(layer "B.Cu")
			(hatch none 0.5)
			(connect_pads
				(clearance 0)
			)
			(min_thickness 0.25)
			(keepout
				(tracks not_allowed)
				(vias allowed)
				(pads allowed)
				(copperpour not_allowed)
				(footprints allowed)
			)
			(placement
				(enabled no)
				(sheetname "")
			)
			(fill
				(thermal_gap 0.5)
				(thermal_bridge_width 0.5)
				(island_removal_mode 0)
			)
			(polygon
				(pts
					(xy 13.74902 -100.71608) (xy 13.74902 -100.20808) (xy 13.36802 -100.20808) (xy 13.36802 -100.71608)
				)
			)
		)
	)
)
